# T6G (Grand Teton) — schematic parts with pin connectivity, parts 2605–2605 of 8303; source: Cadence DE-HDL packaged netlist (pstxprt.dat, pstxnet.dat, pstchip.dat)

J24  SCONN288_DDR506112002KQ  IO  pkg DDR288S_1-1VXC  page 98
  1  VIN_BULK0  POWER  = P12V_MEM_CPU1
  2  RFU0  TRI  = NC
  3  VIN_MGMT  POWER  = P3V3_AUX
  4  HSCL  IN  = I3C_SPD_DDRA_CPU1_SCL
  5  HSDA  BI  = I3C_SPD_DDRA_CPU1_SDA
  6  VSS0  POWER  = GND
  7  DQ0_A  BI  = M_A_CPU1_SA_DQ<0>
  8  VSS1  POWER  = GND
  9  DQ1_A  BI  = M_A_CPU1_SA_DQ<1>
  10  VSS2  POWER  = GND
  11  DQS0_A_T  BI  = M_A_CPU1_SA_DQS_DP<0>
  12  DQS0_A_C  BI  = M_A_CPU1_SA_DQS_DN<0>
  13  VSS3  POWER  = GND
  14  DQ4_A  BI  = M_A_CPU1_SA_DQ<4>
  15  VSS4  POWER  = GND
  16  DQ5_A  BI  = M_A_CPU1_SA_DQ<5>
  17  VSS5  POWER  = GND
  18  DQ8_A  BI  = M_A_CPU1_SA_DQ<8>
  19  VSS6  POWER  = GND
  20  DQ9_A  BI  = M_A_CPU1_SA_DQ<9>
  21  VSS7  POWER  = GND
  22  DQS1_A_T  BI  = M_A_CPU1_SA_DQS_DP<1>
  23  DQS1_A_C  BI  = M_A_CPU1_SA_DQS_DN<1>
  24  VSS8  POWER  = GND
  25  DQ12_A  BI  = M_A_CPU1_SA_DQ<12>
  26  VSS9  POWER  = GND
  27  DQ13_A  BI  = M_A_CPU1_SA_DQ<13>
  28  VSS10  POWER  = GND
  29  DQ16_A  BI  = M_A_CPU1_SA_DQ<16>
  30  VSS11  POWER  = GND
  31  DQ17_A  BI  = M_A_CPU1_SA_DQ<17>
  32  VSS12  POWER  = GND
  33  DQS2_A_T  BI  = M_A_CPU1_SA_DQS_DP<2>
  34  DQS2_A_C  BI  = M_A_CPU1_SA_DQS_DN<2>
  35  VSS13  POWER  = GND
  36  DQ20_A  BI  = M_A_CPU1_SA_DQ<20>
  37  VSS14  POWER  = GND
  38  DQ21_A  BI  = M_A_CPU1_SA_DQ<21>
  39  VSS15  POWER  = GND
  40  DQ24_A  BI  = M_A_CPU1_SA_DQ<24>
  41  VSS16  POWER  = GND
  42  DQ25_A  BI  = M_A_CPU1_SA_DQ<25>
  43  VSS17  POWER  = GND
  44  DQS3_A_T  BI  = M_A_CPU1_SA_DQS_DP<3>
  45  DQS3_A_C  BI  = M_A_CPU1_SA_DQS_DN<3>
  46  VSS18  POWER  = GND
  47  DQ28_A  BI  = M_A_CPU1_SA_DQ<28>
  48  VSS19  POWER  = GND
  49  DQ29_A  BI  = M_A_CPU1_SA_DQ<29>
  50  VSS20  POWER  = GND
  51  CB0_A  BI  = M_A_CPU1_SA_CB<0>
  52  VSS21  POWER  = GND
  53  CB1_A  BI  = M_A_CPU1_SA_CB<1>
  54  VSS22  POWER  = GND
  55  DQS4_A_T  BI  = M_A_CPU1_SA_DQS_DP<4>
  56  DQS4_A_C  BI  = M_A_CPU1_SA_DQS_DN<4>
  57  VSS23  POWER  = GND
  58  CB4_A  BI  = M_A_CPU1_SA_CB<4>
  59  VSS24  POWER  = GND
  60  CB5_A  BI  = M_A_CPU1_SA_CB<5>
  61  VSS25  POWER  = GND
  62  ALERT_N  OUT  = M_A_CPU1_ALERT_N
  63  VSS26  POWER  = GND
  64  CS0_A_N  IN  = M_A_CPU1_SA_CS_N<0>
  65  VSS27  POWER  = GND
  66  CA0_A  IN  = M_A_CPU1_SA_CA<0>
  67  VSS28  POWER  = GND
  68  CA2_A  IN  = M_A_CPU1_SA_CA<2>
  69  VSS29  POWER  = GND
  70  CA4_A  IN  = M_A_CPU1_SA_CA<4>
  71  VSS30  POWER  = GND
  72  CA6_A  IN  = M_A_CPU1_SA_CA<6>
  73  VSS31  POWER  = GND
  74  PAR_A  IN  = M_A_CPU1_SA_PAR
  75  VSS32  POWER  = GND
  76  CA0_B  IN  = M_A_CPU1_SB_CA<0>
  77  VSS33  POWER  = GND
  78  CA2_B  IN  = M_A_CPU1_SB_CA<2>
  79  VSS34  POWER  = GND
  80  CA4_B  IN  = M_A_CPU1_SB_CA<4>
  81  VSS35  POWER  = GND
  82  CA6_B  IN  = M_A_CPU1_SB_CA<6>
  83  VSS36  POWER  = GND
  84  CS0_B_N  IN  = M_A_CPU1_SB_CS_N<0>
  85  VSS37  POWER  = GND
  86  \lbd||rsp_a_n\  OUT  = M_A_CPU1_SA_RSP<0>
  87  \lbs||rsp_b_n\  OUT  = M_A_CPU1_SB_RSP<0>
  88  VSS38  POWER  = GND
  89  CB4_B  BI  = M_A_CPU1_SB_CB<4>
  90  VSS39  POWER  = GND
  91  CB5_B  BI  = M_A_CPU1_SB_CB<5>
  92  VSS40  POWER  = GND
  93  \dqs9_b_t||tdqs9_b_t||dbi4_b_n\  BI  = M_A_CPU1_SB_DQS_DP<9>
  94  \dqs9_b_c||tdqs9_b_c\  BI  = M_A_CPU1_SB_DQS_DN<9>
  95  VSS41  POWER  = GND
  96  CB0_B  BI  = M_A_CPU1_SB_CB<0>
  97  VSS42  POWER  = GND
  98  CB1_B  BI  = M_A_CPU1_SB_CB<1>
  99  VSS43  POWER  = GND
  100  DQ0_B  BI  = M_A_CPU1_SB_DQ<0>
  101  VSS44  POWER  = GND
  102  DQ1_B  BI  = M_A_CPU1_SB_DQ<1>
  103  VSS45  POWER  = GND
  104  DQS0_B_T  BI  = M_A_CPU1_SB_DQS_DP<0>
  105  DQS0_B_C  BI  = M_A_CPU1_SB_DQS_DN<0>
  106  VSS46  POWER  = GND
  107  DQ4_B  BI  = M_A_CPU1_SB_DQ<4>
  108  VSS47  POWER  = GND
  109  DQ5_B  BI  = M_A_CPU1_SB_DQ<5>
  110  VSS48  POWER  = GND
  111  DQ8_B  BI  = M_A_CPU1_SB_DQ<8>
  112  VSS49  POWER  = GND
  113  DQ9_B  BI  = M_A_CPU1_SB_DQ<9>
  114  VSS50  POWER  = GND
  115  DQS1_B_T  BI  = M_A_CPU1_SB_DQS_DP<1>
  116  DQS1_B_C  BI  = M_A_CPU1_SB_DQS_DN<1>
  117  VSS51  POWER  = GND
  118  DQ12_B  BI  = M_A_CPU1_SB_DQ<12>
  119  VSS52  POWER  = GND
  120  DQ13_B  BI  = M_A_CPU1_SB_DQ<13>
  121  VSS53  POWER  = GND
  122  DQ16_B  BI  = M_A_CPU1_SB_DQ<16>
  123  VSS54  POWER  = GND
  124  DQ17_B  BI  = M_A_CPU1_SB_DQ<17>
  125  VSS55  POWER  = GND
  126  DQS2_B_T  BI  = M_A_CPU1_SB_DQS_DP<2>
  127  DQS2_B_C  BI  = M_A_CPU1_SB_DQS_DN<2>
  128  VSS56  POWER  = GND
  129  DQ20_B  BI  = M_A_CPU1_SB_DQ<20>
  130  VSS57  POWER  = GND
  131  DQ21_B  BI  = M_A_CPU1_SB_DQ<21>
  132  VSS58  POWER  = GND
  133  DQ24_B  BI  = M_A_CPU1_SB_DQ<24>
  134  VSS59  POWER  = GND
  135  DQ25_B  BI  = M_A_CPU1_SB_DQ<25>
  136  VSS60  POWER  = GND
  137  DQS3_B_T  BI  = M_A_CPU1_SB_DQS_DP<3>
  138  DQS3_B_C  BI  = M_A_CPU1_SB_DQS_DN<3>
  139  VSS61  POWER  = GND
  140  DQ28_B  BI  = M_A_CPU1_SB_DQ<28>
  141  VSS62  POWER  = GND
  142  DQ29_B  BI  = M_A_CPU1_SB_DQ<29>
  143  VSS63  POWER  = GND
  144  RFU1  TRI  = NC
  145  VIN_BULK1  POWER  = P12V_MEM_CPU1
  146  VIN_BULK2  POWER  = P12V_MEM_CPU1
  147  \pwr_good||fail_n\  BI  = PWRGD_CHA_CPU1_DIMM0
  148  HAS  IN  = PD_CHA_CPU1_DIMM0_SAA
  149  RFU2  TRI  = NC
  150  RFU3  TRI  = NC
  151  VSS64  POWER  = GND
  152  DQ2_A  BI  = M_A_CPU1_SA_DQ<2>
  153  VSS65  POWER  = GND
  154  DQ3_A  BI  = M_A_CPU1_SA_DQ<3>
  155  VSS66  POWER  = GND
  156  \dqs5_a_c||tdqs5_a_c||dqs5_a_t||tdqs5_a_t\  BI  = M_A_CPU1_SA_DQS_DN<5>
  157  \dqs5_a_t||tdqs5_a_t\  BI  = M_A_CPU1_SA_DQS_DP<5>
  158  VSS67  POWER  = GND
  159  DQ6_A  BI  = M_A_CPU1_SA_DQ<6>
  160  VSS68  POWER  = GND
  161  DQ7_A  BI  = M_A_CPU1_SA_DQ<7>
  162  VSS69  POWER  = GND
  163  DQ10_A  BI  = M_A_CPU1_SA_DQ<10>
  164  VSS70  POWER  = GND
  165  DQ11_A  BI  = M_A_CPU1_SA_DQ<11>
  166  VSS71  POWER  = GND
  167  \dqs6_a_c||tdqs6_a_c||dqs6_a_t||tdqs6_a_t\  BI  = M_A_CPU1_SA_DQS_DN<6>
  168  \dqs6_a_t||tdqs6_a_t\  BI  = M_A_CPU1_SA_DQS_DP<6>
  169  VSS72  POWER  = GND
  170  DQ14_A  BI  = M_A_CPU1_SA_DQ<14>
  171  VSS73  POWER  = GND
  172  DQ15_A  BI  = M_A_CPU1_SA_DQ<15>
  173  VSS74  POWER  = GND
  174  DQ18_A  BI  = M_A_CPU1_SA_DQ<18>
  175  VSS75  POWER  = GND
  176  DQ19_A  BI  = M_A_CPU1_SA_DQ<19>
  177  VSS76  POWER  = GND
  178  \dqs7_a_c||tdqs7_a_c\  BI  = M_A_CPU1_SA_DQS_DN<7>
  179  \dqs7_a_t||tdqs7_a_t\  BI  = M_A_CPU1_SA_DQS_DP<7>
  180  VSS77  POWER  = GND
  181  DQ22_A  BI  = M_A_CPU1_SA_DQ<22>
  182  VSS78  POWER  = GND
  183  DQ23_A  BI  = M_A_CPU1_SA_DQ<23>
  184  VSS79  POWER  = GND
  185  DQ26_A  BI  = M_A_CPU1_SA_DQ<26>
  186  VSS80  POWER  = GND
  187  DQ27_A  BI  = M_A_CPU1_SA_DQ<27>
  188  VSS81  POWER  = GND
  189  \dqs8_a_c||tdqs8_a_c\  BI  = M_A_CPU1_SA_DQS_DN<8>
  190  \dqs8_a_t||tdqs8_a_t\  BI  = M_A_CPU1_SA_DQS_DP<8>
  191  VSS82  POWER  = GND
  192  DQ30_A  BI  = M_A_CPU1_SA_DQ<30>
  193  VSS83  POWER  = GND
  194  DQ31_A  BI  = M_A_CPU1_SA_DQ<31>
  195  VSS84  POWER  = GND
  196  CB2_A  BI  = M_A_CPU1_SA_CB<2>
  197  VSS85  POWER  = GND
  198  CB3_A  BI  = M_A_CPU1_SA_CB<3>
  199  VSS86  POWER  = GND
  200  \dqs9_a_c||tdqs9_a_c\  BI  = M_A_CPU1_SA_DQS_DN<9>
  201  \dqs9_a_t||tdqs9_a_t\  BI  = M_A_CPU1_SA_DQS_DP<9>
  202  VSS87  POWER  = GND
  203  CB6_A  BI  = M_A_CPU1_SA_CB<6>
  204  VSS88  POWER  = GND
  205  CB7_A  BI  = M_A_CPU1_SA_CB<7>
  206  VSS89  POWER  = GND
  207  RESET_N  IN  = M_A_CPU1_RESET_N
  208  VSS90  POWER  = GND
  209  CS1_A_N  IN  = M_A_CPU1_SA_CS_N<1>
  210  VSS91  POWER  = GND
  211  CA1_A  IN  = M_A_CPU1_SA_CA<1>
  212  VSS92  POWER  = GND
  213  CA3_A  IN  = M_A_CPU1_SA_CA<3>
  214  VSS93  POWER  = GND
  215  CA5_A  IN  = M_A_CPU1_SA_CA<5>
  216  VSS94  POWER  = GND
  217  CK_T  IN  = M_A_CPU1_CLK_DP<0>
  218  CK_C  IN  = M_A_CPU1_CLK_DN<0>
  219  VSS95  POWER  = GND
  220  RFU4  TRI  = NC
  221  CA1_B  IN  = M_A_CPU1_SB_CA<1>
  222  VSS96  POWER  = GND
  223  CA3_B  IN  = M_A_CPU1_SB_CA<3>
  224  VSS97  POWER  = GND
  225  CA5_B  IN  = M_A_CPU1_SB_CA<5>
  226  VSS98  POWER  = GND
  227  PAR_B  IN  = M_A_CPU1_SB_PAR
  228  VSS99  POWER  = GND
  229  CS1_B_N  IN  = M_A_CPU1_SB_CS_N<1>
  230  VSS100  POWER  = GND
  231  RFU5  TRI  = NC
  232  RFU6  TRI  = NC
  233  VSS101  POWER  = GND
  234  CB6_B  BI  = M_A_CPU1_SB_CB<6>
  235  VSS102  POWER  = GND
  236  CB7_B  BI  = M_A_CPU1_SB_CB<7>
  237  VSS103  POWER  = GND
  238  DQS4_B_C  BI  = M_A_CPU1_SB_DQS_DN<4>
  239  DQS4_B_T  BI  = M_A_CPU1_SB_DQS_DP<4>
  240  VSS104  POWER  = GND
  241  CB2_B  BI  = M_A_CPU1_SB_CB<2>
  242  VSS105  POWER  = GND
  243  CB3_B  BI  = M_A_CPU1_SB_CB<3>
  244  VSS106  POWER  = GND
  245  DQ2_B  BI  = M_A_CPU1_SB_DQ<2>
  246  VSS107  POWER  = GND
  247  DQ3_B  BI  = M_A_CPU1_SB_DQ<3>
  248  VSS108  POWER  = GND
  249  \dqs5_b_c||tdqs5_b_c\  BI  = M_A_CPU1_SB_DQS_DN<5>
  250  \dqs5_b_t||tdqs5_b_t\  BI  = M_A_CPU1_SB_DQS_DP<5>
  251  VSS109  POWER  = GND
  252  DQ6_B  BI  = M_A_CPU1_SB_DQ<6>
  253  VSS110  POWER  = GND
  254  DQ7_B  BI  = M_A_CPU1_SB_DQ<7>
  255  VSS111  POWER  = GND
  256  DQ10_B  BI  = M_A_CPU1_SB_DQ<10>
  257  VSS112  POWER  = GND
  258  DQ11_B  BI  = M_A_CPU1_SB_DQ<11>
  259  VSS113  POWER  = GND
  260  \dqs6_b_c||tdqs6_b_c\  BI  = M_A_CPU1_SB_DQS_DN<6>
  261  \dqs6_b_t||tdqs6_b_t\  BI  = M_A_CPU1_SB_DQS_DP<6>
  262  VSS114  POWER  = GND
  263  DQ14_B  BI  = M_A_CPU1_SB_DQ<14>
  264  VSS115  POWER  = GND
  265  DQ15_B  BI  = M_A_CPU1_SB_DQ<15>
  266  VSS116  POWER  = GND
  267  DQ18_B  BI  = M_A_CPU1_SB_DQ<18>
  268  VSS117  POWER  = GND
  269  DQ19_B  BI  = M_A_CPU1_SB_DQ<19>
  270  VSS118  POWER  = GND
  271  \dqs7_b_c||tdqs7_b_c\  BI  = M_A_CPU1_SB_DQS_DN<7>
  272  \dqs7_b_t||tdqs7_b_t\  BI  = M_A_CPU1_SB_DQS_DP<7>
  273  VSS119  POWER  = GND
  274  DQ22_B  BI  = M_A_CPU1_SB_DQ<22>
  275  VSS120  POWER  = GND
  276  DQ23_B  BI  = M_A_CPU1_SB_DQ<23>
  277  VSS121  POWER  = GND
  278  DQ26_B  BI  = M_A_CPU1_SB_DQ<26>
  279  VSS122  POWER  = GND
  280  DQ27_B  BI  = M_A_CPU1_SB_DQ<27>
  281  VSS123  POWER  = GND
  282  \dqs8_b_c||tdqs8_b_c\  BI  = M_A_CPU1_SB_DQS_DN<8>
  283  \dqs8_b_t||tdqs8_b_t\  BI  = M_A_CPU1_SB_DQS_DP<8>
  284  VSS124  POWER  = GND
  285  DQ30_B  BI  = M_A_CPU1_SB_DQ<30>
  286  VSS125  POWER  = GND
  287  DQ31_B  BI  = M_A_CPU1_SB_DQ<31>
  288  VSS126  POWER  = GND
  G1  G1  POWER  = GND
  G2  G2  POWER  = GND
  G3  G3  POWER  = GND
